# BASEBOARD_FAB2 (Tioga Pass) — schematic netlist excerpt (pin names and nets, part order shuffled) for the footprints in the layout excerpt that follows; sources: Cadence DE-HDL packaged netlist, KiCad conversion of Wiwynn_Tioga_Pass_MB.brd

C8M1  CAP_A  47UF 4V 20% X5R  pkg 0603V  page 228 : A = PVDDQ_KLM ; B = GND
R9N3  RES  0.0 5% CHIP  pkg 0402  page 210 : A = VR_PVSA_CPU1_VCIN ; B = P5V_STBY
C9P18  CAPP  470UF 2.5V 20% ALUM  pkg 3018  page 208 : A = PVCCIN_CPU1 ; B = GND

(kicad_pcb
	(version 20260206)
	(generator "pcbnew")
	(generator_version "10.0")
	(general
		(thickness 1.6)
		(legacy_teardrops no)
	)
	(paper "A4")
	(title_block
		(title "Wiwynn_Tioga_Pass_MB.brd")
		(comment 1 "Tioga Pass / footprints 3378-3380 of 4770")
	)
	(layers
		(0 "F.Cu" signal "TOP")
		(4 "In1.Cu" signal "L2GND")
		(6 "In2.Cu" signal "L3")
		(8 "In3.Cu" signal "L4GND")
		(10 "In4.Cu" signal "L5")
		(12 "In5.Cu" signal "L6GND")
		(14 "In6.Cu" signal "L7VCC")
		(16 "In7.Cu" signal "L8VCC")
		(18 "In8.Cu" signal "L9GND")
		(20 "In9.Cu" signal "L10")
		(22 "In10.Cu" signal "L11GND")
		(24 "In11.Cu" signal "L12")
		(26 "In12.Cu" signal "L13GND")
		(2 "B.Cu" signal "BOTTOM")
		(9 "F.Adhes" user "F.Adhesive")
		(11 "B.Adhes" user "B.Adhesive")
		(13 "F.Paste" user "Package Geometry/Pastemask Top")
		(15 "B.Paste" user "Package Geometry/Pastemask Bottom")
		(5 "F.SilkS" user "Ref Des/Silkscreen Top")
		(7 "B.SilkS" user "Ref Des/Silkscreen Bottom")
		(1 "F.Mask" user "Board Geometry/Soldermask Top")
		(3 "B.Mask" user "Board Geometry/Soldermask Bottom")
		(17 "Dwgs.User" user "User.Drawings")
		(19 "Cmts.User" user "User.Comments")
		(21 "Eco1.User" user "User.Eco1")
		(23 "Eco2.User" user "User.Eco2")
		(25 "Edge.Cuts" user "Board Geometry/Outline")
		(27 "Margin" user)
		(31 "F.CrtYd" user "Package Geometry/Place Bound Top")
		(29 "B.CrtYd" user "Package Geometry/Place Bound Bottom")
		(35 "F.Fab" user "Ref Des/Assembly Top")
		(33 "B.Fab" user "Ref Des/Assembly Bottom")
	)
	(footprint ""
		(layer "B.Cu")
		(at 45.212 -73.279 -90)
		(property "Reference" "C9P18"
			(at -0.98933 -3.81 0)
			(unlocked yes)
			(layer "B.SilkS")
			(effects
				(font
					(size 0.7874 0.5842)
					(thickness 0.1524)
				)
				(justify mirror)
			)
		)
		(property "Value" ""
			(at 0 0 90)
			(layer "B.Fab")
			(effects
				(font
					(size 1.27 1.27)
				)
				(justify mirror)
			)
		)
		(duplicate_pad_numbers_are_jumpers no)
		(fp_line
			(start -2.286 7.366)
			(end -1.600708 7.366)
			(stroke
				(width 0.1524)
				(type default)
			)
			(layer "B.SilkS")
		)
		(fp_line
			(start -2.286 7.366)
			(end -2.286 1.63195)
			(stroke
				(width 0.1524)
				(type default)
			)
			(layer "B.SilkS")
		)
		(fp_line
			(start 2.286 7.366)
			(end 1.60147 7.366)
			(stroke
				(width 0.1524)
				(type default)
			)
			(layer "B.SilkS")
		)
		(fp_line
			(start 2.286 7.366)
			(end 2.286 1.632712)
			(stroke
				(width 0.1524)
				(type default)
			)
			(layer "B.SilkS")
		)
		(fp_line
			(start -2.504948 1.633728)
			(end -1.6002 1.633728)
			(stroke
				(width 0.1524)
				(type default)
			)
			(layer "B.SilkS")
		)
		(fp_line
			(start 2.563114 1.633728)
			(end 1.6002 1.633728)
			(stroke
				(width 0.1524)
				(type default)
			)
			(layer "B.SilkS")
		)
		(fp_line
			(start -2.504948 -1.616456)
			(end -2.504948 1.633728)
			(stroke
				(width 0.1524)
				(type default)
			)
			(layer "B.SilkS")
		)
		(fp_line
			(start -1.6002 -1.616456)
			(end -2.504948 -1.616456)
			(stroke
				(width 0.1524)
				(type default)
			)
			(layer "B.SilkS")
		)
		(fp_line
			(start 1.6002 -1.616456)
			(end 2.563114 -1.616456)
			(stroke
				(width 0.1524)
				(type default)
			)
			(layer "B.SilkS")
		)
		(fp_line
			(start 2.563114 -1.616456)
			(end 2.563114 1.633728)
			(stroke
				(width 0.1524)
				(type default)
			)
			(layer "B.SilkS")
		)
		(fp_rect
			(start 2.286 7.366)
			(end -2.286 -0.254)
			(stroke
				(width 0)
				(type default)
			)
			(fill no)
			(layer "B.CrtYd")
		)
		(fp_line
			(start -2.286 7.366)
			(end 2.286 7.366)
			(stroke
				(width 0.1)
				(type default)
			)
			(layer "B.Fab")
		)
		(fp_line
			(start 2.286 7.366)
			(end 2.286 -0.254)
			(stroke
				(width 0.1)
				(type default)
			)
			(layer "B.Fab")
		)
		(fp_line
			(start -2.286 -0.254)
			(end -2.286 7.366)
			(stroke
				(width 0.1)
				(type default)
			)
			(layer "B.Fab")
		)
		(fp_line
			(start 2.286 -0.254)
			(end -2.286 -0.254)
			(stroke
				(width 0.1)
				(type default)
			)
			(layer "B.Fab")
		)
		(pad "1" smd rect
			(at 0 0 90)
			(size 2.54 3.048)
			(layers "B.Cu" "B.Mask" "B.Paste")
			(net "PVCCIN_CPU1")
		)
		(pad "2" smd rect
			(at 0 7.112 90)
			(size 2.54 3.048)
			(layers "B.Cu" "B.Mask" "B.Paste")
			(net "GND")
		)
	)
	(footprint ""
		(layer "B.Cu")
		(at 104.5591 -135.4074 90)
		(property "Reference" "C8M1"
			(at -1.848866 0.752348 90)
			(unlocked yes)
			(layer "B.SilkS")
			(effects
				(font
					(size 1.27 0.9652)
					(thickness 0.1524)
				)
				(justify mirror)
			)
		)
		(property "Value" ""
			(at 0 0 90)
			(layer "B.Fab")
			(effects
				(font
					(size 1.27 1.27)
				)
				(justify mirror)
			)
		)
		(duplicate_pad_numbers_are_jumpers no)
		(fp_rect
			(start 0.500126 1.598422)
			(end -0.500126 -0.201422)
			(stroke
				(width 0)
				(type default)
			)
			(fill no)
			(layer "B.CrtYd")
		)
		(fp_line
			(start 0.500126 -0.201422)
			(end -0.500126 -0.201422)
			(stroke
				(width 0.1)
				(type default)
			)
			(layer "B.Fab")
		)
		(fp_line
			(start -0.500126 -0.201422)
			(end -0.500126 1.598422)
			(stroke
				(width 0.1)
				(type default)
			)
			(layer "B.Fab")
		)
		(fp_line
			(start 0.500126 1.598422)
			(end 0.500126 -0.201422)
			(stroke
				(width 0.1)
				(type default)
			)
			(layer "B.Fab")
		)
		(fp_line
			(start -0.500126 1.598422)
			(end 0.500126 1.598422)
			(stroke
				(width 0.1)
				(type default)
			)
			(layer "B.Fab")
		)
		(pad "1" smd rect
			(at 0 0)
			(size 0.889 0.9906)
			(layers "B.Cu" "B.Mask" "B.Paste")
			(net "PVDDQ_KLM")
		)
		(pad "2" smd rect
			(at 0 1.397)
			(size 0.889 0.9906)
			(layers "B.Cu" "B.Mask" "B.Paste")
			(net "GND")
		)
		(zone
			(layer "B.Cu")
			(hatch none 0.5)
			(connect_pads
				(clearance 0)
			)
			(min_thickness 0.25)
			(keepout
				(tracks not_allowed)
				(vias allowed)
				(pads allowed)
				(copperpour not_allowed)
				(footprints allowed)
			)
			(placement
				(enabled no)
				(sheetname "")
			)
			(fill
				(thermal_gap 0.5)
				(thermal_bridge_width 0.5)
				(island_removal_mode 0)
			)
			(polygon
				(pts
					(xy 105.5116 -135.9027) (xy 105.0036 -135.9027) (xy 105.0036 -134.9121) (xy 105.5116 -134.9121)
				)
			)
		)
		(zone
			(layer "B.Cu")
			(hatch none 0.5)
			(connect_pads
				(clearance 0)
			)
			(min_thickness 0.25)
			(keepout
				(tracks allowed)
				(vias not_allowed)
				(pads allowed)
				(copperpour not_allowed)
				(footprints allowed)
			)
			(placement
				(enabled no)
				(sheetname "")
			)
			(fill
				(thermal_gap 0.5)
				(thermal_bridge_width 0.5)
				(island_removal_mode 0)
			)
			(polygon
				(pts
					(xy 105.5116 -135.9027) (xy 105.0036 -135.9027) (xy 105.0036 -134.9121) (xy 105.5116 -134.9121)
				)
			)
		)
	)
	(footprint ""
		(layer "B.Cu")
		(at 32.258 -95.1484 90)
		(property "Reference" "R9N3"
			(at 0 0 90)
			(layer "B.SilkS")
			(hide yes)
			(effects
				(font
					(size 1.27 1.27)
				)
				(justify mirror)
			)
		)
		(property "Value" ""
			(at 0 0 90)
			(layer "B.Fab")
			(effects
				(font
					(size 1.27 1.27)
				)
				(justify mirror)
			)
		)
		(duplicate_pad_numbers_are_jumpers no)
		(fp_poly
			(pts
				(xy 0.2794 -0.1016) (xy -0.2794 -0.1016) (xy -0.2794 0.9906) (xy 0.2794 0.9906)
			)
			(stroke
				(width 0)
				(type default)
			)
			(fill no)
			(layer "B.CrtYd")
		)
		(fp_line
			(start 0.2794 -0.1016)
			(end 0.2794 0.9906)
			(stroke
				(width 0.1)
				(type default)
			)
			(layer "B.Fab")
		)
		(fp_line
			(start -0.2794 -0.1016)
			(end 0.2794 -0.1016)
			(stroke
				(width 0.1)
				(type default)
			)
			(layer "B.Fab")
		)
		(fp_line
			(start 0.2794 0.9906)
			(end -0.2794 0.9906)
			(stroke
				(width 0.1)
				(type default)
			)
			(layer "B.Fab")
		)
		(fp_line
			(start -0.2794 0.9906)
			(end -0.2794 -0.1016)
			(stroke
				(width 0.1)
				(type default)
			)
			(layer "B.Fab")
		)
		(pad "1" smd rect
			(at 0 0 270)
			(size 0.508 0.508)
			(layers "B.Cu" "B.Mask" "B.Paste")
			(net "VR_PVSA_CPU1_VCIN")
		)
		(pad "2" smd rect
			(at 0 0.889 270)
			(size 0.508 0.508)
			(layers "B.Cu" "B.Mask" "B.Paste")
			(net "P5V_STBY")
		)
		(zone
			(layer "B.Cu")
			(hatch none 0.5)
			(connect_pads
				(clearance 0)
			)
			(min_thickness 0.25)
			(keepout
				(tracks allowed)
				(vias not_allowed)
				(pads allowed)
				(copperpour not_allowed)
				(footprints allowed)
			)
			(placement
				(enabled no)
				(sheetname "")
			)
			(fill
				(thermal_gap 0.5)
				(thermal_bridge_width 0.5)
				(island_removal_mode 0)
			)
			(polygon
				(pts
					(xy 32.512 -95.4024) (xy 32.512 -94.8944) (xy 32.893 -94.8944) (xy 32.893 -95.4024)
				)
			)
		)
		(zone
			(layer "B.Cu")
			(hatch none 0.5)
			(connect_pads
				(clearance 0)
			)
			(min_thickness 0.25)
			(keepout
				(tracks not_allowed)
				(vias allowed)
				(pads allowed)
				(copperpour not_allowed)
				(footprints allowed)
			)
			(placement
				(enabled no)
				(sheetname "")
			)
			(fill
				(thermal_gap 0.5)
				(thermal_bridge_width 0.5)
				(island_removal_mode 0)
			)
			(polygon
				(pts
					(xy 32.893 -95.4024) (xy 32.893 -94.8944) (xy 32.512 -94.8944) (xy 32.512 -95.4024)
				)
			)
		)
	)
)
